(kicad_pcb
	(version 20260206)
	(generator "pcbnew")
	(generator_version "10.0")
	(general
		(thickness 1.6)
		(legacy_teardrops no)
	)
	(paper "A4")
	(title_block
		(title "12092022_DA0F0TFB6D0_F0T_FAN_BOARD_MP5048_D_brd_v02_OCP.brd")
		(comment 1 "Grand Teton / footprints 104-109 of 924")
	)
	(layers
		(0 "F.Cu" signal "TOP")
		(4 "In1.Cu" signal "GND")
		(6 "In2.Cu" signal "IN1")
		(8 "In3.Cu" signal "IN2")
		(10 "In4.Cu" signal "GND1")
		(2 "B.Cu" signal "BOTTOM")
		(9 "F.Adhes" user "F.Adhesive")
		(11 "B.Adhes" user "B.Adhesive")
		(13 "F.Paste" user "Package Geometry/Pastemask Top")
		(15 "B.Paste" user "Package Geometry/Pastemask Bottom")
		(5 "F.SilkS" user "Ref Des/Silkscreen Top")
		(7 "B.SilkS" user "Ref Des/Silkscreen Bottom")
		(1 "F.Mask" user "Board Geometry/Soldermask Top")
		(3 "B.Mask" user "Board Geometry/Soldermask Bottom")
		(17 "Dwgs.User" user "User.Drawings")
		(19 "Cmts.User" user "User.Comments")
		(21 "Eco1.User" user "User.Eco1")
		(23 "Eco2.User" user "User.Eco2")
		(25 "Edge.Cuts" user "Board Geometry/Outline")
		(27 "Margin" user)
		(31 "F.CrtYd" user "Package Geometry/Place Bound Top")
		(29 "B.CrtYd" user "Package Geometry/Place Bound Bottom")
		(35 "F.Fab" user "Ref Des/Assembly Top")
		(33 "B.Fab" user "Ref Des/Assembly Bottom")
	)
	(footprint ""
		(layer "F.Cu")
		(at 34.417 -143.891 -90)
		(property "Reference" "R4792"
			(at 0 0 270)
			(layer "F.SilkS")
			(hide yes)
			(effects
				(font
					(size 1.27 1.27)
				)
			)
		)
		(property "Value" ""
			(at 0 0 270)
			(layer "F.Fab")
			(effects
				(font
					(size 1.27 1.27)
				)
			)
		)
		(duplicate_pad_numbers_are_jumpers no)
		(fp_line
			(start -0.7874 0.4064)
			(end -0.7874 -0.4064)
			(stroke
				(width 0.1524)
				(type default)
			)
			(layer "F.SilkS")
		)
		(fp_line
			(start 0.7874 0.4064)
			(end -0.7874 0.4064)
			(stroke
				(width 0.1524)
				(type default)
			)
			(layer "F.SilkS")
		)
		(fp_line
			(start -0.7874 -0.4064)
			(end 0.7874 -0.4064)
			(stroke
				(width 0.1524)
				(type default)
			)
			(layer "F.SilkS")
		)
		(fp_line
			(start 0.7874 -0.4064)
			(end 0.7874 0.4064)
			(stroke
				(width 0.1524)
				(type default)
			)
			(layer "F.SilkS")
		)
		(fp_line
			(start -0.67945 0.3048)
			(end -0.67945 -0.305054)
			(stroke
				(width 0.1)
				(type default)
			)
			(layer "F.Fab")
		)
		(fp_line
			(start -0.12065 0.3048)
			(end -0.67945 0.3048)
			(stroke
				(width 0.1)
				(type default)
			)
			(layer "F.Fab")
		)
		(fp_line
			(start 0.120396 0.3048)
			(end 0.120396 0.2794)
			(stroke
				(width 0.1)
				(type default)
			)
			(layer "F.Fab")
		)
		(fp_line
			(start 0.67945 0.3048)
			(end 0.120396 0.3048)
			(stroke
				(width 0.1)
				(type default)
			)
			(layer "F.Fab")
		)
		(fp_line
			(start -0.12065 0.2794)
			(end -0.12065 0.3048)
			(stroke
				(width 0.1)
				(type default)
			)
			(layer "F.Fab")
		)
		(fp_line
			(start 0.120396 0.2794)
			(end -0.12065 0.2794)
			(stroke
				(width 0.1)
				(type default)
			)
			(layer "F.Fab")
		)
		(fp_line
			(start -0.12065 -0.2794)
			(end 0.12065 -0.2794)
			(stroke
				(width 0.1)
				(type default)
			)
			(layer "F.Fab")
		)
		(fp_line
			(start 0.12065 -0.2794)
			(end 0.12065 -0.3048)
			(stroke
				(width 0.1)
				(type default)
			)
			(layer "F.Fab")
		)
		(fp_line
			(start 0.12065 -0.3048)
			(end 0.67945 -0.3048)
			(stroke
				(width 0.1)
				(type default)
			)
			(layer "F.Fab")
		)
		(fp_line
			(start 0.67945 -0.3048)
			(end 0.67945 0.3048)
			(stroke
				(width 0.1)
				(type default)
			)
			(layer "F.Fab")
		)
		(fp_line
			(start -0.67945 -0.305054)
			(end -0.12065 -0.305054)
			(stroke
				(width 0.1)
				(type default)
			)
			(layer "F.Fab")
		)
		(fp_line
			(start -0.12065 -0.305054)
			(end -0.12065 -0.2794)
			(stroke
				(width 0.1)
				(type default)
			)
			(layer "F.Fab")
		)
		(pad "1" smd circle
			(at -0.40005 0 270)
			(size 0 0)
			(layers "F.Cu" "F.Mask" "F.Paste")
			(net "SMB_FAN3_R_SCL")
		)
		(pad "2" smd circle
			(at 0.40005 0 270)
			(size 0 0)
			(layers "F.Cu" "F.Mask" "F.Paste")
			(net "SMB_FAN3_SCL")
		)
	)
	(footprint ""
		(layer "F.Cu")
		(at 37.846 -124.968 180)
		(property "Reference" "R5607"
			(at 0 0 180)
			(layer "F.SilkS")
			(hide yes)
			(effects
				(font
					(size 1.27 1.27)
				)
			)
		)
		(property "Value" ""
			(at 0 0 180)
			(layer "F.Fab")
			(effects
				(font
					(size 1.27 1.27)
				)
			)
		)
		(duplicate_pad_numbers_are_jumpers no)
		(fp_line
			(start 0.7874 0.4064)
			(end -0.7874 0.4064)
			(stroke
				(width 0.1524)
				(type default)
			)
			(layer "F.SilkS")
		)
		(fp_line
			(start 0.7874 -0.4064)
			(end 0.7874 0.4064)
			(stroke
				(width 0.1524)
				(type default)
			)
			(layer "F.SilkS")
		)
		(fp_line
			(start -0.7874 0.4064)
			(end -0.7874 -0.4064)
			(stroke
				(width 0.1524)
				(type default)
			)
			(layer "F.SilkS")
		)
		(fp_line
			(start -0.7874 -0.4064)
			(end 0.7874 -0.4064)
			(stroke
				(width 0.1524)
				(type default)
			)
			(layer "F.SilkS")
		)
		(fp_line
			(start 0.67945 0.3048)
			(end 0.120396 0.3048)
			(stroke
				(width 0.1)
				(type default)
			)
			(layer "F.Fab")
		)
		(fp_line
			(start 0.67945 -0.3048)
			(end 0.67945 0.3048)
			(stroke
				(width 0.1)
				(type default)
			)
			(layer "F.Fab")
		)
		(fp_line
			(start 0.12065 -0.2794)
			(end 0.12065 -0.3048)
			(stroke
				(width 0.1)
				(type default)
			)
			(layer "F.Fab")
		)
		(fp_line
			(start 0.12065 -0.3048)
			(end 0.67945 -0.3048)
			(stroke
				(width 0.1)
				(type default)
			)
			(layer "F.Fab")
		)
		(fp_line
			(start 0.120396 0.3048)
			(end 0.120396 0.2794)
			(stroke
				(width 0.1)
				(type default)
			)
			(layer "F.Fab")
		)
		(fp_line
			(start 0.120396 0.2794)
			(end -0.12065 0.2794)
			(stroke
				(width 0.1)
				(type default)
			)
			(layer "F.Fab")
		)
		(fp_line
			(start -0.12065 0.3048)
			(end -0.67945 0.3048)
			(stroke
				(width 0.1)
				(type default)
			)
			(layer "F.Fab")
		)
		(fp_line
			(start -0.12065 0.2794)
			(end -0.12065 0.3048)
			(stroke
				(width 0.1)
				(type default)
			)
			(layer "F.Fab")
		)
		(fp_line
			(start -0.12065 -0.2794)
			(end 0.12065 -0.2794)
			(stroke
				(width 0.1)
				(type default)
			)
			(layer "F.Fab")
		)
		(fp_line
			(start -0.12065 -0.305054)
			(end -0.12065 -0.2794)
			(stroke
				(width 0.1)
				(type default)
			)
			(layer "F.Fab")
		)
		(fp_line
			(start -0.67945 0.3048)
			(end -0.67945 -0.305054)
			(stroke
				(width 0.1)
				(type default)
			)
			(layer "F.Fab")
		)
		(fp_line
			(start -0.67945 -0.305054)
			(end -0.12065 -0.305054)
			(stroke
				(width 0.1)
				(type default)
			)
			(layer "F.Fab")
		)
		(pad "1" smd rect
			(at -0.40005 0)
			(size 0.4572 0.508)
			(layers "F.Cu" "F.Mask" "F.Paste")
			(net "FAN_3_PWM")
		)
		(pad "2" smd rect
			(at 0.40005 0)
			(size 0.4572 0.508)
			(layers "F.Cu" "F.Mask" "F.Paste")
			(net "FAN_3_PWM_R1")
		)
	)
	(footprint ""
		(layer "F.Cu")
		(at 22.479 -206.248 90)
		(property "Reference" "R344"
			(at 0 0 90)
			(layer "F.SilkS")
			(hide yes)
			(effects
				(font
					(size 1.27 1.27)
				)
			)
		)
		(property "Value" ""
			(at 0 0 90)
			(layer "F.Fab")
			(effects
				(font
					(size 1.27 1.27)
				)
			)
		)
		(duplicate_pad_numbers_are_jumpers no)
		(fp_line
			(start 0.7874 -0.4064)
			(end 0.7874 0.4064)
			(stroke
				(width 0.1524)
				(type default)
			)
			(layer "F.SilkS")
		)
		(fp_line
			(start -0.7874 -0.4064)
			(end 0.7874 -0.4064)
			(stroke
				(width 0.1524)
				(type default)
			)
			(layer "F.SilkS")
		)
		(fp_line
			(start 0.7874 0.4064)
			(end -0.7874 0.4064)
			(stroke
				(width 0.1524)
				(type default)
			)
			(layer "F.SilkS")
		)
		(fp_line
			(start -0.7874 0.4064)
			(end -0.7874 -0.4064)
			(stroke
				(width 0.1524)
				(type default)
			)
			(layer "F.SilkS")
		)
		(fp_line
			(start -0.12065 -0.305054)
			(end -0.12065 -0.2794)
			(stroke
				(width 0.1)
				(type default)
			)
			(layer "F.Fab")
		)
		(fp_line
			(start -0.67945 -0.305054)
			(end -0.12065 -0.305054)
			(stroke
				(width 0.1)
				(type default)
			)
			(layer "F.Fab")
		)
		(fp_line
			(start 0.67945 -0.3048)
			(end 0.67945 0.3048)
			(stroke
				(width 0.1)
				(type default)
			)
			(layer "F.Fab")
		)
		(fp_line
			(start 0.12065 -0.3048)
			(end 0.67945 -0.3048)
			(stroke
				(width 0.1)
				(type default)
			)
			(layer "F.Fab")
		)
		(fp_line
			(start 0.12065 -0.2794)
			(end 0.12065 -0.3048)
			(stroke
				(width 0.1)
				(type default)
			)
			(layer "F.Fab")
		)
		(fp_line
			(start -0.12065 -0.2794)
			(end 0.12065 -0.2794)
			(stroke
				(width 0.1)
				(type default)
			)
			(layer "F.Fab")
		)
		(fp_line
			(start 0.120396 0.2794)
			(end -0.12065 0.2794)
			(stroke
				(width 0.1)
				(type default)
			)
			(layer "F.Fab")
		)
		(fp_line
			(start -0.12065 0.2794)
			(end -0.12065 0.3048)
			(stroke
				(width 0.1)
				(type default)
			)
			(layer "F.Fab")
		)
		(fp_line
			(start 0.67945 0.3048)
			(end 0.120396 0.3048)
			(stroke
				(width 0.1)
				(type default)
			)
			(layer "F.Fab")
		)
		(fp_line
			(start 0.120396 0.3048)
			(end 0.120396 0.2794)
			(stroke
				(width 0.1)
				(type default)
			)
			(layer "F.Fab")
		)
		(fp_line
			(start -0.12065 0.3048)
			(end -0.67945 0.3048)
			(stroke
				(width 0.1)
				(type default)
			)
			(layer "F.Fab")
		)
		(fp_line
			(start -0.67945 0.3048)
			(end -0.67945 -0.305054)
			(stroke
				(width 0.1)
				(type default)
			)
			(layer "F.Fab")
		)
		(pad "1" smd circle
			(at -0.40005 0 90)
			(size 0 0)
			(layers "F.Cu" "F.Mask" "F.Paste")
			(net "P3V3_AUX")
		)
		(pad "2" smd circle
			(at 0.40005 0 90)
			(size 0 0)
			(layers "F.Cu" "F.Mask" "F.Paste")
			(net "FAN_1_PWM")
		)
	)
	(footprint ""
		(layer "F.Cu")
		(at 32.512 -117.094)
		(property "Reference" "R5328"
			(at 0 0 0)
			(layer "F.SilkS")
			(hide yes)
			(effects
				(font
					(size 1.27 1.27)
				)
			)
		)
		(property "Value" ""
			(at 0 0 0)
			(layer "F.Fab")
			(effects
				(font
					(size 1.27 1.27)
				)
			)
		)
		(duplicate_pad_numbers_are_jumpers no)
		(fp_line
			(start -1.2954 -0.5842)
			(end 1.2954 -0.5842)
			(stroke
				(width 0.1524)
				(type default)
			)
			(layer "F.SilkS")
		)
		(fp_line
			(start -1.2954 0.5842)
			(end -1.2954 -0.5842)
			(stroke
				(width 0.1524)
				(type default)
			)
			(layer "F.SilkS")
		)
		(fp_line
			(start 1.2954 -0.5842)
			(end 1.2954 0.5842)
			(stroke
				(width 0.1524)
				(type default)
			)
			(layer "F.SilkS")
		)
		(fp_line
			(start 1.2954 0.5842)
			(end -1.2954 0.5842)
			(stroke
				(width 0.1524)
				(type default)
			)
			(layer "F.SilkS")
		)
		(fp_line
			(start -1.1938 -0.406654)
			(end -0.8636 -0.406654)
			(stroke
				(width 0.1)
				(type default)
			)
			(layer "F.Fab")
		)
		(fp_line
			(start -1.1938 0.4064)
			(end -1.1938 -0.406654)
			(stroke
				(width 0.1)
				(type default)
			)
			(layer "F.Fab")
		)
		(fp_line
			(start -0.8636 -0.4572)
			(end 0.8636 -0.4572)
			(stroke
				(width 0.1)
				(type default)
			)
			(layer "F.Fab")
		)
		(fp_line
			(start -0.8636 -0.406654)
			(end -0.8636 -0.4572)
			(stroke
				(width 0.1)
				(type default)
			)
			(layer "F.Fab")
		)
		(fp_line
			(start -0.8636 0.4064)
			(end -1.1938 0.4064)
			(stroke
				(width 0.1)
				(type default)
			)
			(layer "F.Fab")
		)
		(fp_line
			(start -0.8636 0.4318)
			(end -0.8636 0.4064)
			(stroke
				(width 0.1)
				(type default)
			)
			(layer "F.Fab")
		)
		(fp_line
			(start -0.8636 0.4572)
			(end -0.8636 0.4318)
			(stroke
				(width 0.1)
				(type default)
			)
			(layer "F.Fab")
		)
		(fp_line
			(start 0.8636 -0.4572)
			(end 0.8636 -0.406654)
			(stroke
				(width 0.1)
				(type default)
			)
			(layer "F.Fab")
		)
		(fp_line
			(start 0.8636 -0.406654)
			(end 1.1938 -0.406654)
			(stroke
				(width 0.1)
				(type default)
			)
			(layer "F.Fab")
		)
		(fp_line
			(start 0.8636 0.4064)
			(end 0.8636 0.4572)
			(stroke
				(width 0.1)
				(type default)
			)
			(layer "F.Fab")
		)
		(fp_line
			(start 0.8636 0.4572)
			(end -0.8636 0.4572)
			(stroke
				(width 0.1)
				(type default)
			)
			(layer "F.Fab")
		)
		(fp_line
			(start 1.1938 -0.406654)
			(end 1.1938 0.4064)
			(stroke
				(width 0.1)
				(type default)
			)
			(layer "F.Fab")
		)
		(fp_line
			(start 1.1938 0.4064)
			(end 0.8636 0.4064)
			(stroke
				(width 0.1)
				(type default)
			)
			(layer "F.Fab")
		)
		(pad "1" smd rect
			(at -0.7366 0 270)
			(size 0.7112 0.8128)
			(layers "F.Cu" "F.Mask" "F.Paste")
			(net "P52V_FAN_2")
		)
		(pad "2" smd rect
			(at 0.7366 0 270)
			(size 0.7112 0.8128)
			(layers "F.Cu" "F.Mask" "F.Paste")
			(net "FAN_2_TACH_IL_R")
		)
	)
	(footprint ""
		(layer "F.Cu")
		(at 39.878 -98.806)
		(property "Reference" "U407"
			(at -1.2446 -1.72593 0)
			(unlocked yes)
			(layer "F.SilkS")
			(effects
				(font
					(size 0.7874 0.5842)
					(thickness 0.1524)
				)
				(justify left)
			)
		)
		(property "Value" ""
			(at 0 0 0)
			(layer "F.Fab")
			(effects
				(font
					(size 1.27 1.27)
				)
			)
		)
		(duplicate_pad_numbers_are_jumpers no)
		(fp_line
			(start -1.335278 -1.100074)
			(end -1.335278 1.100074)
			(stroke
				(width 0.1524)
				(type default)
			)
			(layer "F.SilkS")
		)
		(fp_line
			(start -1.335278 1.100074)
			(end 1.335278 1.100074)
			(stroke
				(width 0.1524)
				(type default)
			)
			(layer "F.SilkS")
		)
		(fp_line
			(start 1.335278 -1.100074)
			(end -1.335278 -1.100074)
			(stroke
				(width 0.1524)
				(type default)
			)
			(layer "F.SilkS")
		)
		(fp_line
			(start 1.335278 1.100074)
			(end 1.335278 -1.100074)
			(stroke
				(width 0.1524)
				(type default)
			)
			(layer "F.SilkS")
		)
		(fp_line
			(start -0.674878 -1.100074)
			(end -0.674878 1.100074)
			(stroke
				(width 0.1)
				(type default)
			)
			(layer "F.Fab")
		)
		(fp_line
			(start -0.674878 1.100074)
			(end 0.674878 1.100074)
			(stroke
				(width 0.1)
				(type default)
			)
			(layer "F.Fab")
		)
		(fp_line
			(start 0.674878 -1.100074)
			(end -0.674878 -1.100074)
			(stroke
				(width 0.1)
				(type default)
			)
			(layer "F.Fab")
		)
		(fp_line
			(start 0.674878 1.100074)
			(end 0.674878 -1.100074)
			(stroke
				(width 0.1)
				(type default)
			)
			(layer "F.Fab")
		)
		(pad "D" smd rect
			(at 0.8001 0 270)
			(size 0.6096 0.8128)
			(layers "F.Cu" "F.Mask" "F.Paste")
			(net "U407_D1")
		)
		(pad "G" smd rect
			(at -0.8001 -0.649986 270)
			(size 0.6096 0.8128)
			(layers "F.Cu" "F.Mask" "F.Paste")
			(net "FAN_2_PRESENT")
		)
		(pad "S" smd rect
			(at -0.8001 0.649986 270)
			(size 0.6096 0.8128)
			(layers "F.Cu" "F.Mask" "F.Paste")
			(net "GND")
		)
	)
	(footprint ""
		(layer "F.Cu")
		(at 37.338 -113.595912)
		(property "Reference" "R5222"
			(at 0 0 0)
			(layer "F.SilkS")
			(hide yes)
			(effects
				(font
					(size 1.27 1.27)
				)
			)
		)
		(property "Value" ""
			(at 0 0 0)
			(layer "F.Fab")
			(effects
				(font
					(size 1.27 1.27)
				)
			)
		)
		(duplicate_pad_numbers_are_jumpers no)
		(fp_line
			(start -0.7874 -0.4064)
			(end 0.7874 -0.4064)
			(stroke
				(width 0.1524)
				(type default)
			)
			(layer "F.SilkS")
		)
		(fp_line
			(start -0.7874 0.4064)
			(end -0.7874 -0.4064)
			(stroke
				(width 0.1524)
				(type default)
			)
			(layer "F.SilkS")
		)
		(fp_line
			(start 0.7874 -0.4064)
			(end 0.7874 0.4064)
			(stroke
				(width 0.1524)
				(type default)
			)
			(layer "F.SilkS")
		)
		(fp_line
			(start 0.7874 0.4064)
			(end -0.7874 0.4064)
			(stroke
				(width 0.1524)
				(type default)
			)
			(layer "F.SilkS")
		)
		(fp_line
			(start -0.67945 -0.305054)
			(end -0.12065 -0.305054)
			(stroke
				(width 0.1)
				(type default)
			)
			(layer "F.Fab")
		)
		(fp_line
			(start -0.67945 0.3048)
			(end -0.67945 -0.305054)
			(stroke
				(width 0.1)
				(type default)
			)
			(layer "F.Fab")
		)
		(fp_line
			(start -0.12065 -0.305054)
			(end -0.12065 -0.2794)
			(stroke
				(width 0.1)
				(type default)
			)
			(layer "F.Fab")
		)
		(fp_line
			(start -0.12065 -0.2794)
			(end 0.12065 -0.2794)
			(stroke
				(width 0.1)
				(type default)
			)
			(layer "F.Fab")
		)
		(fp_line
			(start -0.12065 0.2794)
			(end -0.12065 0.3048)
			(stroke
				(width 0.1)
				(type default)
			)
			(layer "F.Fab")
		)
		(fp_line
			(start -0.12065 0.3048)
			(end -0.67945 0.3048)
			(stroke
				(width 0.1)
				(type default)
			)
			(layer "F.Fab")
		)
		(fp_line
			(start 0.120396 0.2794)
			(end -0.12065 0.2794)
			(stroke
				(width 0.1)
				(type default)
			)
			(layer "F.Fab")
		)
		(fp_line
			(start 0.120396 0.3048)
			(end 0.120396 0.2794)
			(stroke
				(width 0.1)
				(type default)
			)
			(layer "F.Fab")
		)
		(fp_line
			(start 0.12065 -0.3048)
			(end 0.67945 -0.3048)
			(stroke
				(width 0.1)
				(type default)
			)
			(layer "F.Fab")
		)
		(fp_line
			(start 0.12065 -0.2794)
			(end 0.12065 -0.3048)
			(stroke
				(width 0.1)
				(type default)
			)
			(layer "F.Fab")
		)
		(fp_line
			(start 0.67945 -0.3048)
			(end 0.67945 0.3048)
			(stroke
				(width 0.1)
				(type default)
			)
			(layer "F.Fab")
		)
		(fp_line
			(start 0.67945 0.3048)
			(end 0.120396 0.3048)
			(stroke
				(width 0.1)
				(type default)
			)
			(layer "F.Fab")
		)
		(pad "1" smd circle
			(at -0.40005 0)
			(size 0 0)
			(layers "F.Cu" "F.Mask" "F.Paste")
			(net "SMB_FAN2_SCL")
		)
		(pad "2" smd circle
			(at 0.40005 0)
			(size 0 0)
			(layers "F.Cu" "F.Mask" "F.Paste")
			(net "SMB_FAN2_SCL_R")
		)
	)
)
